(kicad_pcb
	(version 20241229)
	(generator "pcbnew")
	(generator_version "9.0")
	(general
		(thickness 1.61)
		(legacy_teardrops no)
	)
	(paper "A3")
	(title_block
		(title "RDIMM DDR5 Tester")
		(date "2026-05-21")
		(rev "2.2.0")
		(company "Antmicro")
		(comment 9 "footprints 750-754 of 796")
	)
	(layers
		(0 "F.Cu" signal)
		(4 "In1.Cu" power)
		(6 "In2.Cu" mixed)
		(8 "In3.Cu" power)
		(10 "In4.Cu" mixed)
		(12 "In5.Cu" power)
		(14 "In6.Cu" mixed)
		(16 "In7.Cu" power)
		(18 "In8.Cu" power)
		(20 "In9.Cu" mixed)
		(22 "In10.Cu" power)
		(2 "B.Cu" signal)
		(9 "F.Adhes" user "F.Adhesive")
		(11 "B.Adhes" user "B.Adhesive")
		(13 "F.Paste" user)
		(15 "B.Paste" user)
		(5 "F.SilkS" user "F.Silkscreen")
		(7 "B.SilkS" user "B.Silkscreen")
		(1 "F.Mask" user)
		(3 "B.Mask" user)
		(17 "Dwgs.User" user "User.Drawings")
		(19 "Cmts.User" user "User.Comments")
		(21 "Eco1.User" user "User.Eco1")
		(23 "Eco2.User" user "User.Eco2")
		(25 "Edge.Cuts" user)
		(27 "Margin" user)
		(31 "F.CrtYd" user "F.Courtyard")
		(29 "B.CrtYd" user "B.Courtyard")
		(35 "F.Fab" user)
		(33 "B.Fab" user)
	)
	(footprint "antmicro-footprints:Fiducial_1mm_Mask2mm"
		(layer "B.Cu")
		(at 113.585 186.315 180)
		(descr "Circular Fiducial, 1mm bare copper, 3mm soldermask opening")
		(tags "fiducial")
		(property "Reference" "FID1001"
			(at 0 1.4 0)
			(layer "B.SilkS")
			(hide yes)
			(effects
				(font
					(size 0.7 0.7)
					(thickness 0.15)
				)
				(justify left bottom mirror)
			)
		)
		(property "Value" "Fiducial_1mm_Mask2mm"
			(at 0 -2.2 0)
			(layer "B.Fab")
			(effects
				(font
					(size 0.7 0.7)
					(thickness 0.15)
				)
				(justify left bottom mirror)
			)
		)
		(sheetfile "data-center-rdimm-ddr5-tester.kicad_sch")
		(attr board_only exclude_from_pos_files exclude_from_bom)
		(fp_circle
			(center 0 0)
			(end 1.24 0)
			(stroke
				(width 0.05)
				(type solid)
			)
			(fill no)
			(layer "B.CrtYd")
		)
		(fp_circle
			(center 0 0)
			(end 0.999 0)
			(stroke
				(width 0.15)
				(type solid)
			)
			(fill no)
			(layer "B.Fab")
		)
		(fp_text user "License: Apache-2.0"
			(at -1.25 -7.003 0)
			(layer "B.Fab")
			(effects
				(font
					(size 0.7 0.7)
					(thickness 0.15)
				)
				(justify left bottom mirror)
			)
		)
		(fp_text user "${REFERENCE}"
			(at -1.25 -4.603 0)
			(layer "B.Fab")
			(effects
				(font
					(size 0.7 0.7)
					(thickness 0.15)
				)
				(justify left bottom mirror)
			)
		)
		(fp_text user "Author: Antmicro"
			(at -1.25 -5.803 0)
			(layer "B.Fab")
			(effects
				(font
					(size 0.7 0.7)
					(thickness 0.15)
				)
				(justify left bottom mirror)
			)
		)
		(pad "" smd circle
			(at 0 0 180)
			(size 1 1)
			(layers "B.Cu" "B.Mask")
			(solder_mask_margin 0.5)
			(clearance 0.5)
		)
	)
	(footprint "antmicro-footprints:C_0402_1005Metric"
		(layer "B.Cu")
		(at 187.49 167.45 90)
		(descr "Capacitor SMD 0402")
		(tags "capacitor SMD 0402")
		(property "Reference" "C276"
			(at -4 0.724 90)
			(layer "B.SilkS")
			(effects
				(font
					(size 0.7 0.7)
					(thickness 0.15)
				)
				(justify right bottom mirror)
			)
		)
		(property "Value" "C_100n_0402"
			(at -1.022927 -2.155213 90)
			(layer "B.Fab")
			(effects
				(font
					(size 0.7 0.7)
					(thickness 0.15)
				)
				(justify right bottom mirror)
			)
		)
		(property "Datasheet" "https://www.murata.com/products/productdetail?partno=GRM155R61H104KE14%23"
			(at 0 0 90)
			(layer "F.Fab")
			(hide yes)
			(effects
				(font
					(size 1.27 1.27)
					(thickness 0.15)
				)
			)
		)
		(property "Manufacturer" "Murata"
			(at 0 0 90)
			(unlocked yes)
			(layer "B.Fab")
			(hide yes)
			(effects
				(font
					(size 1 1)
					(thickness 0.15)
				)
				(justify mirror)
			)
		)
		(property "MPN" "GRM155R61H104KE14D"
			(at 0 0 90)
			(unlocked yes)
			(layer "B.Fab")
			(hide yes)
			(effects
				(font
					(size 1 1)
					(thickness 0.15)
				)
				(justify mirror)
			)
		)
		(property "Val" "100n"
			(at 0 0 90)
			(unlocked yes)
			(layer "B.Fab")
			(hide yes)
			(effects
				(font
					(size 1 1)
					(thickness 0.15)
				)
				(justify mirror)
			)
		)
		(property "License" "Apache-2.0"
			(at 0 0 90)
			(unlocked yes)
			(layer "B.Fab")
			(hide yes)
			(effects
				(font
					(size 1 1)
					(thickness 0.15)
				)
				(justify mirror)
			)
		)
		(property "Author" "Antmicro"
			(at 0 0 90)
			(unlocked yes)
			(layer "B.Fab")
			(hide yes)
			(effects
				(font
					(size 1 1)
					(thickness 0.15)
				)
				(justify mirror)
			)
		)
		(property "Voltage" "50V"
			(at 0 0 90)
			(unlocked yes)
			(layer "B.Fab")
			(hide yes)
			(effects
				(font
					(size 1 1)
					(thickness 0.15)
				)
				(justify mirror)
			)
		)
		(property "Dielectric" "X5R"
			(at 0 0 90)
			(unlocked yes)
			(layer "B.Fab")
			(hide yes)
			(effects
				(font
					(size 1 1)
					(thickness 0.15)
				)
				(justify mirror)
			)
		)
		(sheetname "/FPGA MGT Interface/")
		(sheetfile "fpga-mgt.kicad_sch")
		(attr smd)
		(fp_rect
			(start -0.925 0.47)
			(end 0.925 -0.47)
			(stroke
				(width 0.05)
				(type default)
			)
			(fill no)
			(layer "B.CrtYd")
		)
		(fp_line
			(start 0.504 -0.248)
			(end -0.494 -0.248)
			(stroke
				(width 0.15)
				(type solid)
			)
			(layer "B.Fab")
		)
		(fp_line
			(start -0.494 -0.248)
			(end -0.494 0.25)
			(stroke
				(width 0.15)
				(type solid)
			)
			(layer "B.Fab")
		)
		(fp_line
			(start 0.504 0.25)
			(end 0.504 -0.248)
			(stroke
				(width 0.15)
				(type solid)
			)
			(layer "B.Fab")
		)
		(fp_line
			(start -0.494 0.25)
			(end 0.504 0.25)
			(stroke
				(width 0.15)
				(type solid)
			)
			(layer "B.Fab")
		)
		(fp_text user "License: Apache-2.0"
			(at -0.939 -5.799 270)
			(layer "B.Fab")
			(effects
				(font
					(size 0.7 0.7)
					(thickness 0.15)
				)
				(justify left bottom mirror)
			)
		)
		(fp_text user "${REFERENCE}"
			(at -0.939 -4.599 270)
			(layer "B.Fab")
			(effects
				(font
					(size 0.7 0.7)
					(thickness 0.15)
				)
				(justify left bottom mirror)
			)
		)
		(fp_text user "Author: Antmicro"
			(at -0.939 -3.399 270)
			(layer "B.Fab")
			(effects
				(font
					(size 0.7 0.7)
					(thickness 0.15)
				)
				(justify left bottom mirror)
			)
		)
		(pad "1" smd roundrect
			(at -0.48 0 90)
			(size 0.59 0.64)
			(layers "B.Cu" "B.Mask" "B.Paste")
			(roundrect_rratio 0.25)
			(net 248 "/FPGA MGT Interface/HDMI_OUT.D0_N")
			(pintype "passive")
		)
		(pad "2" smd roundrect
			(at 0.48 0 90)
			(size 0.59 0.64)
			(layers "B.Cu" "B.Mask" "B.Paste")
			(roundrect_rratio 0.25)
			(net 631 "/FPGA MGT Interface/HDMI_FPGA.TX0_N")
			(pintype "passive")
		)
	)
	(footprint "antmicro-footprints:R_0402_1005Metric"
		(layer "B.Cu")
		(at 238.424499 181.449 180)
		(descr "Resistor SMD 0402")
		(tags "resistor SMD 0402")
		(property "Reference" "R178"
			(at -3.95 -0.5 0)
			(layer "B.SilkS")
			(effects
				(font
					(size 0.7 0.7)
					(thickness 0.15)
				)
				(justify left bottom mirror)
			)
		)
		(property "Value" "R_0R_0402"
			(at -1.011843 -1.772047 0)
			(layer "B.Fab")
			(effects
				(font
					(size 0.7 0.7)
					(thickness 0.15)
				)
				(justify left bottom mirror)
			)
		)
		(property "Datasheet" "https://industrial.panasonic.com/cdbs/www-data/pdf/RDA0000/AOA0000C301.pdf"
			(at 0 0 180)
			(layer "F.Fab")
			(hide yes)
			(effects
				(font
					(size 1.27 1.27)
					(thickness 0.15)
				)
			)
		)
		(property "Manufacturer" "Panasonic"
			(at 0 0 180)
			(unlocked yes)
			(layer "B.Fab")
			(hide yes)
			(effects
				(font
					(size 1 1)
					(thickness 0.15)
				)
				(justify mirror)
			)
		)
		(property "MPN" "ERJ2GE0R00X"
			(at 0 0 180)
			(unlocked yes)
			(layer "B.Fab")
			(hide yes)
			(effects
				(font
					(size 1 1)
					(thickness 0.15)
				)
				(justify mirror)
			)
		)
		(property "Val" "0R"
			(at 0 0 180)
			(unlocked yes)
			(layer "B.Fab")
			(hide yes)
			(effects
				(font
					(size 1 1)
					(thickness 0.15)
				)
				(justify mirror)
			)
		)
		(property "License" "Apache-2.0"
			(at 0 0 180)
			(unlocked yes)
			(layer "B.Fab")
			(hide yes)
			(effects
				(font
					(size 1 1)
					(thickness 0.15)
				)
				(justify mirror)
			)
		)
		(property "Author" "Antmicro"
			(at 0 0 180)
			(unlocked yes)
			(layer "B.Fab")
			(hide yes)
			(effects
				(font
					(size 1 1)
					(thickness 0.15)
				)
				(justify mirror)
			)
		)
		(property "Tolerance" "~"
			(at 0 0 180)
			(unlocked yes)
			(layer "B.Fab")
			(hide yes)
			(effects
				(font
					(size 1 1)
					(thickness 0.15)
				)
				(justify mirror)
			)
		)
		(property "Current" "1A"
			(at 0 0 180)
			(unlocked yes)
			(layer "B.Fab")
			(hide yes)
			(effects
				(font
					(size 1 1)
					(thickness 0.15)
				)
				(justify mirror)
			)
		)
		(sheetname "/I^{2}C + I3C/")
		(sheetfile "i2c.kicad_sch")
		(attr smd exclude_from_bom dnp)
		(fp_rect
			(start -0.925 0.47)
			(end 0.925 -0.47)
			(stroke
				(width 0.05)
				(type default)
			)
			(fill no)
			(layer "B.CrtYd")
		)
		(fp_rect
			(start -0.5 0.25)
			(end 0.5 -0.25)
			(stroke
				(width 0.15)
				(type solid)
			)
			(fill no)
			(layer "B.Fab")
		)
		(fp_text user "Author: Antmicro"
			(at -0.95 -4.169 0)
			(layer "B.Fab")
			(effects
				(font
					(size 0.7 0.7)
					(thickness 0.15)
				)
				(justify left bottom mirror)
			)
		)
		(fp_text user "License: Apache-2.0"
			(at -0.95 -5.169 0)
			(layer "B.Fab")
			(effects
				(font
					(size 0.7 0.7)
					(thickness 0.15)
				)
				(justify left bottom mirror)
			)
		)
		(fp_text user "${REFERENCE}"
			(at -0.95 -3.168 0)
			(layer "B.Fab")
			(effects
				(font
					(size 0.7 0.7)
					(thickness 0.15)
				)
				(justify left bottom mirror)
			)
		)
		(pad "1" smd roundrect
			(at -0.48 0 180)
			(size 0.59 0.64)
			(layers "B.Cu" "B.Mask" "B.Paste")
			(roundrect_rratio 0.25)
			(net 749 "/I^{2}C + I3C/PWR.SCL")
			(pintype "passive")
		)
		(pad "2" smd roundrect
			(at 0.48 0 180)
			(size 0.59 0.64)
			(layers "B.Cu" "B.Mask" "B.Paste")
			(roundrect_rratio 0.25)
			(net 747 "/FPGA Config/FPGA_PWR.SCL")
			(pintype "passive")
		)
	)
	(footprint "antmicro-footprints:C_0805_2012Metric"
		(layer "B.Cu")
		(at 230.005 187.67)
		(descr "Capacitor SMD 0805")
		(tags "capacitor SMD 0805")
		(property "Reference" "C202"
			(at 1.945 1.13 0)
			(layer "B.SilkS")
			(effects
				(font
					(size 0.7 0.7)
					(thickness 0.15)
				)
				(justify right bottom mirror)
			)
		)
		(property "Value" "C_22u_25V_0805"
			(at -2.055717 -1.963152 0)
			(layer "B.Fab")
			(effects
				(font
					(size 0.7 0.7)
					(thickness 0.15)
				)
				(justify right bottom mirror)
			)
		)
		(property "Datasheet" "https://product.samsungsem.com/mlcc/CL21A226MAYNNN.do"
			(at 0 0 0)
			(layer "F.Fab")
			(hide yes)
			(effects
				(font
					(size 1.27 1.27)
					(thickness 0.15)
				)
			)
		)
		(property "MPN" "CL21A226MAYNNNE"
			(at 0 0 0)
			(unlocked yes)
			(layer "B.Fab")
			(hide yes)
			(effects
				(font
					(size 1 1)
					(thickness 0.15)
				)
				(justify mirror)
			)
		)
		(property "Manufacturer" "Samsung Electro-Mechanics"
			(at 0 0 0)
			(unlocked yes)
			(layer "B.Fab")
			(hide yes)
			(effects
				(font
					(size 1 1)
					(thickness 0.15)
				)
				(justify mirror)
			)
		)
		(property "License" "Apache-2.0"
			(at 0 0 0)
			(unlocked yes)
			(layer "B.Fab")
			(hide yes)
			(effects
				(font
					(size 1 1)
					(thickness 0.15)
				)
				(justify mirror)
			)
		)
		(property "Author" "Antmicro"
			(at 0 0 0)
			(unlocked yes)
			(layer "B.Fab")
			(hide yes)
			(effects
				(font
					(size 1 1)
					(thickness 0.15)
				)
				(justify mirror)
			)
		)
		(property "Val" "22u"
			(at 0 0 0)
			(unlocked yes)
			(layer "B.Fab")
			(hide yes)
			(effects
				(font
					(size 1 1)
					(thickness 0.15)
				)
				(justify mirror)
			)
		)
		(property "Voltage" "25V"
			(at 0 0 0)
			(unlocked yes)
			(layer "B.Fab")
			(hide yes)
			(effects
				(font
					(size 1 1)
					(thickness 0.15)
				)
				(justify mirror)
			)
		)
		(property "Dielectric" "X5R"
			(at 0 0 0)
			(unlocked yes)
			(layer "B.Fab")
			(hide yes)
			(effects
				(font
					(size 1 1)
					(thickness 0.15)
				)
				(justify mirror)
			)
		)
		(property "Public" "False"
			(at 0 0 0)
			(unlocked yes)
			(layer "B.Fab")
			(hide yes)
			(effects
				(font
					(size 1 1)
					(thickness 0.15)
				)
				(justify mirror)
			)
		)
		(sheetname "/Supply/DC-DC VCCINT/")
		(sheetfile "dc-dc-vccint.kicad_sch")
		(attr smd)
		(fp_line
			(start -0.3 -0.7)
			(end 0.3 -0.7)
			(stroke
				(width 0.15)
				(type solid)
			)
			(layer "B.SilkS")
		)
		(fp_line
			(start -0.3 0.7)
			(end 0.3 0.7)
			(stroke
				(width 0.15)
				(type solid)
			)
			(layer "B.SilkS")
		)
		(fp_rect
			(start 1.95 0.9)
			(end -1.95 -0.9)
			(stroke
				(width 0.05)
				(type default)
			)
			(fill no)
			(layer "B.CrtYd")
		)
		(fp_rect
			(start -0.95 0.675)
			(end 0.95 -0.675)
			(stroke
				(width 0.15)
				(type solid)
			)
			(fill no)
			(layer "B.Fab")
		)
		(fp_text user "${REFERENCE}"
			(at -1.9 -3.947 180)
			(layer "B.Fab")
			(effects
				(font
					(size 0.7 0.7)
					(thickness 0.15)
				)
				(justify left bottom mirror)
			)
		)
		(fp_text user "License: Apache-2.0"
			(at -1.9 -4.947 180)
			(layer "B.Fab")
			(effects
				(font
					(size 0.7 0.7)
					(thickness 0.15)
				)
				(justify left bottom mirror)
			)
		)
		(fp_text user "Author: Antmicro"
			(at -1.9 -5.947 180)
			(layer "B.Fab")
			(effects
				(font
					(size 0.7 0.7)
					(thickness 0.15)
				)
				(justify left bottom mirror)
			)
		)
		(pad "1" smd roundrect
			(at -1.1 0)
			(size 1.2 1.3)
			(layers "B.Cu" "B.Mask" "B.Paste")
			(roundrect_rratio 0.25)
			(net 1 "GND")
			(pintype "passive")
		)
		(pad "2" smd roundrect
			(at 1.1 0)
			(size 1.2 1.3)
			(layers "B.Cu" "B.Mask" "B.Paste")
			(roundrect_rratio 0.25)
			(net 35 "VDC")
			(pintype "passive")
		)
	)
	(footprint "antmicro-footprints:R_0402_1005Metric_EIA"
		(layer "B.Cu")
		(at 196.51 158)
		(descr "Resistor SMD 0402 (1005 Metric), square (rectangular) end terminal, IPC_7351 nominal, (Body size source: IPC-SM-782 page 76, https://www.pcb-3d.com/wordpress/wp-content/uploads/ipc-sm-782a_amendment_1_and_2.pdf)")
		(tags "resistor 0402")
		(property "Reference" "R18"
			(at -29.885 -10.35 180)
			(layer "B.SilkS")
			(effects
				(font
					(size 0.7 0.7)
					(thickness 0.15)
				)
				(justify left bottom mirror)
			)
		)
		(property "Value" "R_4k7_0402"
			(at 0 -1.169 180)
			(layer "B.Fab")
			(effects
				(font
					(size 0.7 0.7)
					(thickness 0.15)
				)
				(justify left bottom mirror)
			)
		)
		(property "Datasheet" "https://www.bourns.com/docs/product-datasheets/cr.pdf"
			(at 0 0 0)
			(layer "F.Fab")
			(hide yes)
			(effects
				(font
					(size 1.27 1.27)
					(thickness 0.15)
				)
			)
		)
		(property "Manufacturer" "Bourns"
			(at 0 0 0)
			(unlocked yes)
			(layer "B.Fab")
			(hide yes)
			(effects
				(font
					(size 1 1)
					(thickness 0.15)
				)
				(justify mirror)
			)
		)
		(property "MPN" "CR0402-FX-4701GLF"
			(at 0 0 0)
			(unlocked yes)
			(layer "B.Fab")
			(hide yes)
			(effects
				(font
					(size 1 1)
					(thickness 0.15)
				)
				(justify mirror)
			)
		)
		(property "Val" "4k7"
			(at 0 0 0)
			(unlocked yes)
			(layer "B.Fab")
			(hide yes)
			(effects
				(font
					(size 1 1)
					(thickness 0.15)
				)
				(justify mirror)
			)
		)
		(property "License" "Apache-2.0"
			(at 0 0 0)
			(unlocked yes)
			(layer "B.Fab")
			(hide yes)
			(effects
				(font
					(size 1 1)
					(thickness 0.15)
				)
				(justify mirror)
			)
		)
		(property "Author" "Antmicro"
			(at 0 0 0)
			(unlocked yes)
			(layer "B.Fab")
			(hide yes)
			(effects
				(font
					(size 1 1)
					(thickness 0.15)
				)
				(justify mirror)
			)
		)
		(property "Tolerance" "1%"
			(at 0 0 0)
			(unlocked yes)
			(layer "B.Fab")
			(hide yes)
			(effects
				(font
					(size 1 1)
					(thickness 0.15)
				)
				(justify mirror)
			)
		)
		(sheetname "/FPGA Config/")
		(sheetfile "fpga-config.kicad_sch")
		(attr smd)
		(fp_rect
			(start -0.95 0.45)
			(end 0.95 -0.45)
			(stroke
				(width 0.05)
				(type default)
			)
			(fill no)
			(layer "B.CrtYd")
		)
		(fp_line
			(start -0.5 -0.249)
			(end -0.5 0.25)
			(stroke
				(width 0.15)
				(type solid)
			)
			(layer "B.Fab")
		)
		(fp_line
			(start -0.5 0.25)
			(end 0.499 0.25)
			(stroke
				(width 0.15)
				(type solid)
			)
			(layer "B.Fab")
		)
		(fp_line
			(start 0.499 -0.249)
			(end -0.5 -0.249)
			(stroke
				(width 0.15)
				(type solid)
			)
			(layer "B.Fab")
		)
		(fp_line
			(start 0.499 0.25)
			(end 0.499 -0.249)
			(stroke
				(width 0.15)
				(type solid)
			)
			(layer "B.Fab")
		)
		(fp_text user "Author: Antmicro"
			(at -0.95 -5.569 180)
			(layer "B.Fab")
			(effects
				(font
					(size 0.7 0.7)
					(thickness 0.15)
				)
				(justify left bottom mirror)
			)
		)
		(fp_text user "License: Apache-2.0"
			(at -0.95 -4.369 180)
			(layer "B.Fab")
			(effects
				(font
					(size 0.7 0.7)
					(thickness 0.15)
				)
				(justify left bottom mirror)
			)
		)
		(fp_text user "${REFERENCE}"
			(at -0.95 -3.169 180)
			(layer "B.Fab")
			(effects
				(font
					(size 0.7 0.7)
					(thickness 0.15)
				)
				(justify left bottom mirror)
			)
		)
		(pad "1" smd roundrect
			(at -0.5 0 270)
			(size 0.6 0.6)
			(layers "B.Cu" "B.Mask" "B.Paste")
			(roundrect_rratio 0.25)
			(net 797 "+1V8")
			(pintype "passive")
		)
		(pad "2" smd roundrect
			(at 0.499 0)
			(size 0.6 0.6)
			(layers "B.Cu" "B.Mask" "B.Paste")
			(roundrect_rratio 0.25)
			(net 357 "/FPGA Config/PROGRAM_B")
			(pintype "passive")
		)
	)
)
